FILE_TYPE = MACRO_DRAWING;
SET COLOR_WIRE YELLOW;
SET COLOR_PROP MONO;
SET COLOR_DOT WHITE;
SET COLOR_ARC YELLOW;
SET COLOR_BODY GREEN;
SET COLOR_NOTE MONO;
SET PROP_DISPLAY VALUE;
SET PAGE_NUMBER P9;
FORCEADD INTEL_CORP_BPAGE..1
(4250 200);
FORCEPROP 1 LAST CUSTOM_TXT_CDS <CURRENT_DESIGN_SHEET> OF <TOTAL_DESIGN_SHEETS>
J 0
(3750 225);
PAINT GREEN (3750 225);
FORCEPROP 1 LAST CUSTOM_TXT_CDS <CON_LAST_MODIFIED>
J 0
(2325 550);
PAINT GREEN (2325 550);
FORCEPROP 2 LAST CUSTOM_TXT_CDS <XR_PAGE_TITLE>
J 0
(-3640 5450);
DISPLAY 0.638298 (-3640 5450);
PAINT PINK (-3640 5450);
DISPLAY INVISIBLE (-3640 5450);
FORCEPROP 1 LAST SCH_ADDRESS2 P.O. BOX 58119
J 0
(275 275);
DISPLAY 0.617021 (275 275);
PAINT GREEN (275 275);
FORCEPROP 1 LAST SCH_ADDRESS1 2200 Mission College Blvd.
J 0
(275 325);
DISPLAY 0.617021 (275 325);
PAINT GREEN (275 325);
FORCEPROP 1 LAST SCH_ADDRESS3 Santa Clara, CA 95052-8119
J 0
(275 225);
DISPLAY 0.617021 (275 225);
PAINT GREEN (275 225);
FORCEPROP 1 LAST SCH_TITLE POWER BLOCK DIAGRAM
J 0
(-3700 250);
DISPLAY 1.212766 (-3700 250);
PAINT ORANGE (-3700 250);
FORCEPROP 1 LAST SCH_REV 2.420
J 0
(4000 350);
DISPLAY 0.978723 (4000 350);
PAINT YELLOW (4000 350);
FORCEPROP 1 LAST SCH_DEPT BESD
J 1
(-200 300);
DISPLAY 1.212766 (-200 300);
PAINT YELLOW (-200 300);
FORCEPROP 1 LAST SCH_NUMBER H4694802
J 0
(2950 350);
DISPLAY 1.212766 (2950 350);
PAINT YELLOW (2950 350);
FORCEPROP 2 LAST PAGE_BORDER TRUE
J 0
(-3640 5450);
DISPLAY 0.638298 (-3640 5450);
PAINT PINK (-3640 5450);
DISPLAY INVISIBLE (-3640 5450);
FORCEPROP 2 LAST CDS_LIB mstr_symbols
J 0
(4250 200);
PAINT MONO (4250 200);
DISPLAY INVISIBLE (4250 200);
FORCEPROP 1 LAST COMMENT_BODY TRUE
J 0
(4262 212);
DISPLAY 0.468085 (4262 212);
PAINT GREEN (4262 212);
DISPLAY INVISIBLE (4262 212);
FORCEPROP 1 LAST CDS_CON_LAST_MODIFIED Tue Dec 01 11:47:57 2015
J 0
(2825 525);
PAINT ORANGE (2825 525);
DISPLAY INVISIBLE (2825 525);
FORCEPROP 2 LAST CDS_XR_PAGE_TITLE CR-9 : @BASEBOARD_FAB2_LIB.BASEBOARD_FAB2(SCH_1):PAGE9
J 0
(-3640 5450);
DISPLAY 0.638298 (-3640 5450);
PAINT PINK (-3640 5450);
DISPLAY INVISIBLE (-3640 5450);
FORCENOTE
$CDS_IMAGE|09_POWER DISTRIBUITION.jpg|5250|5250
(-300 2825) 0;
DISPLAY CENTER (-300 2825);
PAINT MONO (-300 2825);
QUIT
